FILE_TYPE=LIBRARY_PARTS;
primitive 'CONN3_210HP1030BR1';
  pin
    '3':
      PIN_NUMBER='(3)';
      BIDIRECTIONAL='TRUE';
      INPUT_LOAD='(-0.01,0.01)';
      OUTPUT_LOAD='(1.0,-1.0)';
    '2':
      PIN_NUMBER='(2)';
      BIDIRECTIONAL='TRUE';
      INPUT_LOAD='(-0.01,0.01)';
      OUTPUT_LOAD='(1.0,-1.0)';
    '1':
      PIN_NUMBER='(1)';
      BIDIRECTIONAL='TRUE';
      INPUT_LOAD='(-0.01,0.01)';
      OUTPUT_LOAD='(1.0,-1.0)';
  end_pin;
  body
    PART_NAME='CONN3_210HP1030BR1';
    BODY_NAME='CONN3_210HP1030BR1';
    PHYS_DES_PREFIX='JP';
    CLASS='IO';
  end_body;
end_primitive;

END.
